(kicad_pcb
	(version 20260206)
	(generator "pcbnew")
	(generator_version "10.0")
	(general
		(thickness 1.6)
		(legacy_teardrops no)
	)
	(paper "A4")
	(title_block
		(title "pdpb — Lightning_PDPB_BRD.brd")
		(comment 1 "Lightning (Wiwynn / Facebook NVMe JBOF) / footprints 252-257 of 1140")
	)
	(layers
		(0 "F.Cu" signal "TOP")
		(4 "In1.Cu" signal "L2GND")
		(6 "In2.Cu" signal "L3")
		(8 "In3.Cu" signal "L4VCC")
		(10 "In4.Cu" signal "L5VCC")
		(12 "In5.Cu" signal "L6")
		(14 "In6.Cu" signal "L7GND")
		(2 "B.Cu" signal "BOTTOM")
		(9 "F.Adhes" user "F.Adhesive")
		(11 "B.Adhes" user "B.Adhesive")
		(13 "F.Paste" user "Package Geometry/Pastemask Top")
		(15 "B.Paste" user "Package Geometry/Pastemask Bottom")
		(5 "F.SilkS" user "Ref Des/Silkscreen Top")
		(7 "B.SilkS" user "Ref Des/Silkscreen Bottom")
		(1 "F.Mask" user "Board Geometry/Soldermask Top")
		(3 "B.Mask" user "Board Geometry/Soldermask Bottom")
		(17 "Dwgs.User" user "User.Drawings")
		(19 "Cmts.User" user "User.Comments")
		(21 "Eco1.User" user "User.Eco1")
		(23 "Eco2.User" user "User.Eco2")
		(25 "Edge.Cuts" user "Board Geometry/Outline")
		(27 "Margin" user)
		(31 "F.CrtYd" user "Package Geometry/Place Bound Top")
		(29 "B.CrtYd" user "Package Geometry/Place Bound Bottom")
		(35 "F.Fab" user "Ref Des/Assembly Top")
		(33 "B.Fab" user "Ref Des/Assembly Bottom")
	)
	(footprint ""
		(layer "F.Cu")
		(at 24.003 -54.47411 -90)
		(property "Reference" "SR1149"
			(at 0 0 270)
			(layer "F.SilkS")
			(hide yes)
			(effects
				(font
					(size 1.27 1.27)
				)
			)
		)
		(property "Value" "4K7R2F-GP"
			(at 0.064008 -3.993896 270)
			(unlocked yes)
			(layer "F.Fab")
			(hide yes)
			(effects
				(font
					(size 1.016 1.016)
					(thickness 0.1524)
				)
			)
		)
		(property "Device Type" "R402H16"
			(at 0.064008 -5.517896 270)
			(unlocked yes)
			(layer "F.Fab")
			(hide yes)
			(effects
				(font
					(size 1.016 1.016)
					(thickness 0.1524)
				)
			)
		)
		(duplicate_pad_numbers_are_jumpers no)
		(fp_line
			(start -0.508 -0.9398)
			(end -0.508 0.9398)
			(stroke
				(width 0.1524)
				(type default)
			)
			(layer "F.SilkS")
		)
		(fp_line
			(start 0.508 -0.9398)
			(end -0.508 -0.9398)
			(stroke
				(width 0.1524)
				(type default)
			)
			(layer "F.SilkS")
		)
		(fp_rect
			(start -0.508 0.9398)
			(end 0.508 -0.9398)
			(stroke
				(width 0)
				(type default)
			)
			(fill no)
			(layer "F.CrtYd")
		)
		(fp_rect
			(start -0.508 0.9398)
			(end 0.508 -0.9398)
			(stroke
				(width 0)
				(type default)
			)
			(fill no)
			(layer "F.Fab")
		)
		(pad "1" smd custom
			(at 0 -0.4445 270)
			(size 0.1397 0.1397)
			(layers "F.Cu" "F.Mask" "F.Paste")
			(net "P3V3")
			(options
				(clearance outline)
				(anchor circle)
			)
			(primitives
				(gr_poly
					(pts
						(arc
							(start -0.1778 -0.2794)
							(mid -0.249642 -0.249642)
							(end -0.2794 -0.1778)
						)
						(arc
							(start -0.2794 0.1778)
							(mid -0.249642 0.249642)
							(end -0.1778 0.2794)
						)
						(arc
							(start 0.1778 0.2794)
							(mid 0.249642 0.249642)
							(end 0.2794 0.1778)
						)
						(arc
							(start 0.2794 -0.1778)
							(mid 0.249642 -0.249642)
							(end 0.1778 -0.2794)
						)
					)
					(width 0)
					(fill yes)
				)
			)
		)
		(pad "2" smd custom
			(at 0 0.4445 270)
			(size 0.1397 0.1397)
			(layers "F.Cu" "F.Mask" "F.Paste")
			(net "SSD14_CLK0_OE_MOS_N")
			(options
				(clearance outline)
				(anchor circle)
			)
			(primitives
				(gr_poly
					(pts
						(arc
							(start -0.1778 -0.2794)
							(mid -0.249642 -0.249642)
							(end -0.2794 -0.1778)
						)
						(arc
							(start -0.2794 0.1778)
							(mid -0.249642 0.249642)
							(end -0.1778 0.2794)
						)
						(arc
							(start 0.1778 0.2794)
							(mid 0.249642 0.249642)
							(end 0.2794 0.1778)
						)
						(arc
							(start 0.2794 -0.1778)
							(mid 0.249642 -0.249642)
							(end 0.1778 -0.2794)
						)
					)
					(width 0)
					(fill yes)
				)
			)
		)
	)
	(footprint ""
		(layer "F.Cu")
		(at 80.137 -354.076 180)
		(property "Reference" "SR1052"
			(at 0 0 180)
			(layer "F.SilkS")
			(hide yes)
			(effects
				(font
					(size 1.27 1.27)
				)
			)
		)
		(property "Value" "4K7R2F-GP"
			(at 0.064008 -3.993896 180)
			(unlocked yes)
			(layer "F.Fab")
			(hide yes)
			(effects
				(font
					(size 1.016 1.016)
					(thickness 0.1524)
				)
			)
		)
		(property "Device Type" "R402H16"
			(at 0.064008 -5.517896 180)
			(unlocked yes)
			(layer "F.Fab")
			(hide yes)
			(effects
				(font
					(size 1.016 1.016)
					(thickness 0.1524)
				)
			)
		)
		(duplicate_pad_numbers_are_jumpers no)
		(fp_line
			(start 0.508 -0.9398)
			(end -0.508 -0.9398)
			(stroke
				(width 0.1524)
				(type default)
			)
			(layer "F.SilkS")
		)
		(fp_line
			(start -0.508 -0.9398)
			(end -0.508 0.9398)
			(stroke
				(width 0.1524)
				(type default)
			)
			(layer "F.SilkS")
		)
		(fp_rect
			(start -0.508 0.9398)
			(end 0.508 -0.9398)
			(stroke
				(width 0)
				(type default)
			)
			(fill no)
			(layer "F.CrtYd")
		)
		(fp_rect
			(start -0.508 0.9398)
			(end 0.508 -0.9398)
			(stroke
				(width 0)
				(type default)
			)
			(fill no)
			(layer "F.Fab")
		)
		(pad "1" smd custom
			(at 0 -0.4445 180)
			(size 0.1397 0.1397)
			(layers "F.Cu" "F.Mask" "F.Paste")
			(net "P3V3")
			(options
				(clearance outline)
				(anchor circle)
			)
			(primitives
				(gr_poly
					(pts
						(arc
							(start -0.1778 -0.2794)
							(mid -0.249642 -0.249642)
							(end -0.2794 -0.1778)
						)
						(arc
							(start -0.2794 0.1778)
							(mid -0.249642 0.249642)
							(end -0.1778 0.2794)
						)
						(arc
							(start 0.1778 0.2794)
							(mid 0.249642 0.249642)
							(end 0.2794 0.1778)
						)
						(arc
							(start 0.2794 -0.1778)
							(mid 0.249642 -0.249642)
							(end 0.1778 -0.2794)
						)
					)
					(width 0)
					(fill yes)
				)
			)
		)
		(pad "2" smd custom
			(at 0 0.4445 180)
			(size 0.1397 0.1397)
			(layers "F.Cu" "F.Mask" "F.Paste")
			(net "I2C_SW_EU17_ADDRESS_A1")
			(options
				(clearance outline)
				(anchor circle)
			)
			(primitives
				(gr_poly
					(pts
						(arc
							(start -0.1778 -0.2794)
							(mid -0.249642 -0.249642)
							(end -0.2794 -0.1778)
						)
						(arc
							(start -0.2794 0.1778)
							(mid -0.249642 0.249642)
							(end -0.1778 0.2794)
						)
						(arc
							(start 0.1778 0.2794)
							(mid 0.249642 0.249642)
							(end 0.2794 0.1778)
						)
						(arc
							(start 0.2794 -0.1778)
							(mid 0.249642 -0.249642)
							(end 0.1778 -0.2794)
						)
					)
					(width 0)
					(fill yes)
				)
			)
		)
	)
	(footprint ""
		(layer "F.Cu")
		(at 17.123156 -160.010348)
		(property "Reference" "R9953"
			(at 0 0 0)
			(layer "F.SilkS")
			(hide yes)
			(effects
				(font
					(size 1.27 1.27)
				)
			)
		)
		(property "Value" "4K7R2J-2-GP"
			(at 0.064008 -3.993896 0)
			(unlocked yes)
			(layer "F.Fab")
			(hide yes)
			(effects
				(font
					(size 1.016 1.016)
					(thickness 0.1524)
				)
			)
		)
		(property "Device Type" "R402H16"
			(at 0.064008 -5.517896 0)
			(unlocked yes)
			(layer "F.Fab")
			(hide yes)
			(effects
				(font
					(size 1.016 1.016)
					(thickness 0.1524)
				)
			)
		)
		(duplicate_pad_numbers_are_jumpers no)
		(fp_line
			(start -0.508 -0.9398)
			(end -0.508 0.9398)
			(stroke
				(width 0.1524)
				(type default)
			)
			(layer "F.SilkS")
		)
		(fp_line
			(start 0.508 -0.9398)
			(end -0.508 -0.9398)
			(stroke
				(width 0.1524)
				(type default)
			)
			(layer "F.SilkS")
		)
		(fp_rect
			(start -0.508 0.9398)
			(end 0.508 -0.9398)
			(stroke
				(width 0)
				(type default)
			)
			(fill no)
			(layer "F.CrtYd")
		)
		(fp_rect
			(start -0.508 0.9398)
			(end 0.508 -0.9398)
			(stroke
				(width 0)
				(type default)
			)
			(fill no)
			(layer "F.Fab")
		)
		(pad "1" smd custom
			(at 0 -0.4445)
			(size 0.1397 0.1397)
			(layers "F.Cu" "F.Mask" "F.Paste")
			(net "P3V3")
			(options
				(clearance outline)
				(anchor circle)
			)
			(primitives
				(gr_poly
					(pts
						(arc
							(start -0.1778 -0.2794)
							(mid -0.249642 -0.249642)
							(end -0.2794 -0.1778)
						)
						(arc
							(start -0.2794 0.1778)
							(mid -0.249642 0.249642)
							(end -0.1778 0.2794)
						)
						(arc
							(start 0.1778 0.2794)
							(mid 0.249642 0.249642)
							(end 0.2794 0.1778)
						)
						(arc
							(start 0.2794 -0.1778)
							(mid 0.249642 -0.249642)
							(end 0.1778 -0.2794)
						)
					)
					(width 0)
					(fill yes)
				)
			)
		)
		(pad "2" smd custom
			(at 0 0.4445)
			(size 0.1397 0.1397)
			(layers "F.Cu" "F.Mask" "F.Paste")
			(net "ATTN_LED_DR13_MOS_N")
			(options
				(clearance outline)
				(anchor circle)
			)
			(primitives
				(gr_poly
					(pts
						(arc
							(start -0.1778 -0.2794)
							(mid -0.249642 -0.249642)
							(end -0.2794 -0.1778)
						)
						(arc
							(start -0.2794 0.1778)
							(mid -0.249642 0.249642)
							(end -0.1778 0.2794)
						)
						(arc
							(start 0.1778 0.2794)
							(mid 0.249642 0.249642)
							(end 0.2794 0.1778)
						)
						(arc
							(start 0.2794 -0.1778)
							(mid 0.249642 -0.249642)
							(end 0.1778 -0.2794)
						)
					)
					(width 0)
					(fill yes)
				)
			)
		)
	)
	(footprint ""
		(layer "F.Cu")
		(at 19.547332 -262.002778 90)
		(property "Reference" "Q90"
			(at 0 0 90)
			(layer "F.SilkS")
			(hide yes)
			(effects
				(font
					(size 1.27 1.27)
				)
			)
		)
		(property "Value" "2N7002A-7-GP"
			(at 0.127 -8.9662 90)
			(unlocked yes)
			(layer "F.Fab")
			(hide yes)
			(effects
				(font
					(size 1.016 1.016)
					(thickness 0.1524)
				)
			)
		)
		(property "Device Type" "SOT23DGS2D4H48"
			(at 0.127 -10.4902 90)
			(unlocked yes)
			(layer "F.Fab")
			(hide yes)
			(effects
				(font
					(size 1.016 1.016)
					(thickness 0.1524)
				)
			)
		)
		(duplicate_pad_numbers_are_jumpers no)
		(fp_line
			(start 1.651 -1.778)
			(end -1.651 -1.778)
			(stroke
				(width 0.1524)
				(type default)
			)
			(layer "F.SilkS")
		)
		(fp_line
			(start -1.651 -1.778)
			(end -1.651 1.778)
			(stroke
				(width 0.1524)
				(type default)
			)
			(layer "F.SilkS")
		)
		(fp_line
			(start 1.651 1.778)
			(end 1.651 -1.778)
			(stroke
				(width 0.1524)
				(type default)
			)
			(layer "F.SilkS")
		)
		(fp_line
			(start -1.651 1.778)
			(end 1.651 1.778)
			(stroke
				(width 0.1524)
				(type default)
			)
			(layer "F.SilkS")
		)
		(fp_poly
			(pts
				(xy -1.778 1.8796) (xy -1.778 -1.8796) (xy 1.778 -1.8796) (xy 1.778 1.8796)
			)
			(stroke
				(width 0)
				(type default)
			)
			(fill no)
			(layer "F.CrtYd")
		)
		(fp_poly
			(pts
				(xy -1.778 1.8796) (xy -1.778 -1.8796) (xy 1.778 -1.8796) (xy 1.778 1.8796)
			)
			(stroke
				(width 0)
				(type default)
			)
			(fill no)
			(layer "F.Fab")
		)
		(pad "D" smd custom
			(at 0 -0.9525 90)
			(size 0.1905 0.1905)
			(layers "F.Cu" "F.Mask" "F.Paste")
			(net "ATTN_LED_DR12_MOS_N")
			(options
				(clearance outline)
				(anchor circle)
			)
			(primitives
				(gr_poly
					(pts
						(arc
							(start -0.1778 0.5715)
							(mid -0.321484 0.511984)
							(end -0.381 0.3683)
						)
						(arc
							(start -0.381 -0.3683)
							(mid -0.321484 -0.511984)
							(end -0.1778 -0.5715)
						)
						(arc
							(start 0.1778 -0.5715)
							(mid 0.321484 -0.511984)
							(end 0.381 -0.3683)
						)
						(arc
							(start 0.381 0.3683)
							(mid 0.321484 0.511984)
							(end 0.1778 0.5715)
						)
					)
					(width 0)
					(fill yes)
				)
			)
		)
		(pad "G" smd custom
			(at -0.98425 0.9525 90)
			(size 0.1905 0.1905)
			(layers "F.Cu" "F.Mask" "F.Paste")
			(net "SSD12_CLK0_OE_MOS_N")
			(options
				(clearance outline)
				(anchor circle)
			)
			(primitives
				(gr_poly
					(pts
						(arc
							(start -0.1778 0.5715)
							(mid -0.321484 0.511984)
							(end -0.381 0.3683)
						)
						(arc
							(start -0.381 -0.3683)
							(mid -0.321484 -0.511984)
							(end -0.1778 -0.5715)
						)
						(arc
							(start 0.1778 -0.5715)
							(mid 0.321484 -0.511984)
							(end 0.381 -0.3683)
						)
						(arc
							(start 0.381 0.3683)
							(mid 0.321484 0.511984)
							(end 0.1778 0.5715)
						)
					)
					(width 0)
					(fill yes)
				)
			)
		)
		(pad "S" smd custom
			(at 0.98425 0.9525 90)
			(size 0.1905 0.1905)
			(layers "F.Cu" "F.Mask" "F.Paste")
			(net "ATTN_LED_DR12_R")
			(options
				(clearance outline)
				(anchor circle)
			)
			(primitives
				(gr_poly
					(pts
						(arc
							(start -0.1778 0.5715)
							(mid -0.321484 0.511984)
							(end -0.381 0.3683)
						)
						(arc
							(start -0.381 -0.3683)
							(mid -0.321484 -0.511984)
							(end -0.1778 -0.5715)
						)
						(arc
							(start 0.1778 -0.5715)
							(mid 0.321484 -0.511984)
							(end 0.381 -0.3683)
						)
						(arc
							(start 0.381 0.3683)
							(mid 0.321484 0.511984)
							(end 0.1778 0.5715)
						)
					)
					(width 0)
					(fill yes)
				)
			)
		)
	)
	(footprint ""
		(layer "F.Cu")
		(at 84.455 -96.774 90)
		(property "Reference" "R425"
			(at 0 0 90)
			(layer "F.SilkS")
			(hide yes)
			(effects
				(font
					(size 1.27 1.27)
				)
			)
		)
		(property "Value" "0R2J-2-GP"
			(at 0.064008 -3.993896 90)
			(unlocked yes)
			(layer "F.Fab")
			(hide yes)
			(effects
				(font
					(size 1.016 1.016)
					(thickness 0.1524)
				)
			)
		)
		(property "Device Type" "R402H16"
			(at 0.064008 -5.517896 90)
			(unlocked yes)
			(layer "F.Fab")
			(hide yes)
			(effects
				(font
					(size 1.016 1.016)
					(thickness 0.1524)
				)
			)
		)
		(duplicate_pad_numbers_are_jumpers no)
		(fp_line
			(start 0.508 -0.9398)
			(end -0.508 -0.9398)
			(stroke
				(width 0.1524)
				(type default)
			)
			(layer "F.SilkS")
		)
		(fp_line
			(start -0.508 -0.9398)
			(end -0.508 0.9398)
			(stroke
				(width 0.1524)
				(type default)
			)
			(layer "F.SilkS")
		)
		(fp_rect
			(start -0.508 0.9398)
			(end 0.508 -0.9398)
			(stroke
				(width 0)
				(type default)
			)
			(fill no)
			(layer "F.CrtYd")
		)
		(fp_rect
			(start -0.508 0.9398)
			(end 0.508 -0.9398)
			(stroke
				(width 0)
				(type default)
			)
			(fill no)
			(layer "F.Fab")
		)
		(pad "1" smd custom
			(at 0 -0.4445 90)
			(size 0.1397 0.1397)
			(layers "F.Cu" "F.Mask" "F.Paste")
			(net "BMC_I2C_SCL_BUF_8")
			(options
				(clearance outline)
				(anchor circle)
			)
			(primitives
				(gr_poly
					(pts
						(arc
							(start -0.1778 -0.2794)
							(mid -0.249642 -0.249642)
							(end -0.2794 -0.1778)
						)
						(arc
							(start -0.2794 0.1778)
							(mid -0.249642 0.249642)
							(end -0.1778 0.2794)
						)
						(arc
							(start 0.1778 0.2794)
							(mid 0.249642 0.249642)
							(end 0.2794 0.1778)
						)
						(arc
							(start 0.2794 -0.1778)
							(mid 0.249642 -0.249642)
							(end 0.1778 -0.2794)
						)
					)
					(width 0)
					(fill yes)
				)
			)
		)
		(pad "2" smd custom
			(at 0 0.4445 90)
			(size 0.1397 0.1397)
			(layers "F.Cu" "F.Mask" "F.Paste")
			(net "I2C_SCL_BUF_8_EU4_R")
			(options
				(clearance outline)
				(anchor circle)
			)
			(primitives
				(gr_poly
					(pts
						(arc
							(start -0.1778 -0.2794)
							(mid -0.249642 -0.249642)
							(end -0.2794 -0.1778)
						)
						(arc
							(start -0.2794 0.1778)
							(mid -0.249642 0.249642)
							(end -0.1778 0.2794)
						)
						(arc
							(start 0.1778 0.2794)
							(mid 0.249642 0.249642)
							(end 0.2794 0.1778)
						)
						(arc
							(start 0.2794 -0.1778)
							(mid 0.249642 -0.249642)
							(end 0.1778 -0.2794)
						)
					)
					(width 0)
					(fill yes)
				)
			)
		)
	)
	(footprint ""
		(layer "F.Cu")
		(at 43.50004 -144.100042)
		(property "Reference" "LED8"
			(at 0 0 0)
			(layer "F.SilkS")
			(hide yes)
			(effects
				(font
					(size 1.27 1.27)
				)
			)
		)
		(property "Value" "LED-RB-4-GP"
			(at 5.88899 1.80848 0)
			(unlocked yes)
			(layer "F.Fab")
			(hide yes)
			(effects
				(font
					(size 1.016 1.016)
					(thickness 0.1524)
				)
			)
		)
		(property "Device Type" "LED1613-4PH20"
			(at 5.88899 0.28448 0)
			(unlocked yes)
			(layer "F.Fab")
			(hide yes)
			(effects
				(font
					(size 1.016 1.016)
					(thickness 0.1524)
				)
			)
		)
		(duplicate_pad_numbers_are_jumpers no)
		(fp_line
			(start -1.4478 -0.9652)
			(end 1.4478 -0.9652)
			(stroke
				(width 0.1524)
				(type default)
			)
			(layer "F.SilkS")
		)
		(fp_line
			(start -1.4478 0.9652)
			(end -1.4478 -0.9652)
			(stroke
				(width 0.1524)
				(type default)
			)
			(layer "F.SilkS")
		)
		(fp_line
			(start -1.4478 0.9652)
			(end -1.4478 -0.9652)
			(stroke
				(width 0.508)
				(type default)
			)
			(layer "F.SilkS")
		)
		(fp_line
			(start 1.4478 -0.9652)
			(end 1.4478 0.9652)
			(stroke
				(width 0.1524)
				(type default)
			)
			(layer "F.SilkS")
		)
		(fp_line
			(start 1.4478 0.9652)
			(end -1.4478 0.9652)
			(stroke
				(width 0.1524)
				(type default)
			)
			(layer "F.SilkS")
		)
		(fp_rect
			(start -0.8001 0.6477)
			(end 0.8001 -0.6477)
			(stroke
				(width 0)
				(type default)
			)
			(fill no)
			(layer "F.CrtYd")
		)
		(fp_poly
			(pts
				(xy -1.7018 1.2192) (xy -1.7018 -0.06223) (xy -0.8001 -0.06223) (xy -0.8001 0.6477) (xy 0.8001 0.6477)
				(xy 0.8001 -0.6477) (xy -0.8001 -0.6477) (xy -0.8001 -0.0635) (xy -1.7018 -0.0635) (xy -1.7018 -1.2192)
				(xy 1.7018 -1.2192) (xy 1.7018 1.2192)
			)
			(stroke
				(width 0)
				(type default)
			)
			(fill no)
			(layer "F.CrtYd")
		)
		(fp_rect
			(start -1.7018 1.2192)
			(end 1.7018 -1.2192)
			(stroke
				(width 0)
				(type default)
			)
			(fill no)
			(layer "F.Fab")
		)
		(pad "1" smd rect
			(at -0.73025 0.4064)
			(size 0.9144 0.6096)
			(layers "F.Cu" "F.Mask" "F.Paste")
			(net "SSD_ACT_DR8_MOS_N")
		)
		(pad "2" smd rect
			(at -0.73025 -0.4064)
			(size 0.9144 0.6096)
			(layers "F.Cu" "F.Mask" "F.Paste")
			(net "ATTN_LED_DR8_MOS_N")
		)
		(pad "3" smd rect
			(at 0.73025 -0.4064)
			(size 0.9144 0.6096)
			(layers "F.Cu" "F.Mask" "F.Paste")
			(net "DRV_ATTN_8")
		)
		(pad "4" smd rect
			(at 0.73025 0.4064)
			(size 0.9144 0.6096)
			(layers "F.Cu" "F.Mask" "F.Paste")
			(net "DRV_ACT_8")
		)
	)
)
